(kicad_pcb
	(version 20260206)
	(generator "pcbnew")
	(generator_version "10.0")
	(general
		(thickness 1.6)
		(legacy_teardrops no)
	)
	(paper "A4")
	(title_block
		(title "fcb — 12433-1M.1206WZS1330.brd")
		(comment 1 "Open Vault / Knox (Wiwynn) / footprints 334-340 of 495")
	)
	(layers
		(0 "F.Cu" signal "TOP")
		(4 "In1.Cu" signal "L2GND")
		(6 "In2.Cu" signal "L3VCC")
		(2 "B.Cu" signal "BOTTOM")
		(9 "F.Adhes" user "F.Adhesive")
		(11 "B.Adhes" user "B.Adhesive")
		(13 "F.Paste" user "Package Geometry/Pastemask Top")
		(15 "B.Paste" user "Package Geometry/Pastemask Bottom")
		(5 "F.SilkS" user "Ref Des/Silkscreen Top")
		(7 "B.SilkS" user "Ref Des/Silkscreen Bottom")
		(1 "F.Mask" user "Board Geometry/Soldermask Top")
		(3 "B.Mask" user "Board Geometry/Soldermask Bottom")
		(17 "Dwgs.User" user "User.Drawings")
		(19 "Cmts.User" user "User.Comments")
		(21 "Eco1.User" user "User.Eco1")
		(23 "Eco2.User" user "User.Eco2")
		(25 "Edge.Cuts" user "Board Geometry/Outline")
		(27 "Margin" user)
		(31 "F.CrtYd" user "Package Geometry/Place Bound Top")
		(29 "B.CrtYd" user "Package Geometry/Place Bound Bottom")
		(35 "F.Fab" user "Ref Des/Assembly Top")
		(33 "B.Fab" user "Ref Des/Assembly Bottom")
	)
	(footprint ""
		(layer "F.Cu")
		(at 44.069 -178.0794 90)
		(property "Reference" "R270"
			(at 0 0 90)
			(layer "F.SilkS")
			(hide yes)
			(effects
				(font
					(size 1.27 1.27)
				)
			)
		)
		(property "Value" "0R2J-2-GP"
			(at 0.064008 -3.993896 90)
			(unlocked yes)
			(layer "F.Fab")
			(hide yes)
			(effects
				(font
					(size 1.016 1.016)
					(thickness 0.1524)
				)
			)
		)
		(property "Device Type" "R402H16"
			(at 0.064008 -5.517896 90)
			(unlocked yes)
			(layer "F.Fab")
			(hide yes)
			(effects
				(font
					(size 1.016 1.016)
					(thickness 0.1524)
				)
			)
		)
		(duplicate_pad_numbers_are_jumpers no)
		(fp_line
			(start 0.508 -0.9398)
			(end -0.508 -0.9398)
			(stroke
				(width 0.1524)
				(type default)
			)
			(layer "F.SilkS")
		)
		(fp_line
			(start -0.508 -0.9398)
			(end -0.508 0.9398)
			(stroke
				(width 0.1524)
				(type default)
			)
			(layer "F.SilkS")
		)
		(fp_rect
			(start -0.508 0.9398)
			(end 0.508 -0.9398)
			(stroke
				(width 0)
				(type default)
			)
			(fill no)
			(layer "F.CrtYd")
		)
		(fp_rect
			(start -0.508 0.9398)
			(end 0.508 -0.9398)
			(stroke
				(width 0)
				(type default)
			)
			(fill no)
			(layer "F.Fab")
		)
		(pad "1" smd custom
			(at 0 -0.4445 90)
			(size 0.1397 0.1397)
			(layers "F.Cu" "F.Mask" "F.Paste")
			(net "D_LATCH_Q")
			(options
				(clearance outline)
				(anchor circle)
			)
			(primitives
				(gr_poly
					(pts
						(arc
							(start -0.1778 -0.2794)
							(mid -0.249642 -0.249642)
							(end -0.2794 -0.1778)
						)
						(arc
							(start -0.2794 0.1778)
							(mid -0.249642 0.249642)
							(end -0.1778 0.2794)
						)
						(arc
							(start 0.1778 0.2794)
							(mid 0.249642 0.249642)
							(end 0.2794 0.1778)
						)
						(arc
							(start 0.2794 -0.1778)
							(mid 0.249642 -0.249642)
							(end 0.1778 -0.2794)
						)
					)
					(width 0)
					(fill yes)
				)
			)
		)
		(pad "2" smd custom
			(at 0 0.4445 90)
			(size 0.1397 0.1397)
			(layers "F.Cu" "F.Mask" "F.Paste")
			(net "ADM1276_EN")
			(options
				(clearance outline)
				(anchor circle)
			)
			(primitives
				(gr_poly
					(pts
						(arc
							(start -0.1778 -0.2794)
							(mid -0.249642 -0.249642)
							(end -0.2794 -0.1778)
						)
						(arc
							(start -0.2794 0.1778)
							(mid -0.249642 0.249642)
							(end -0.1778 0.2794)
						)
						(arc
							(start 0.1778 0.2794)
							(mid 0.249642 0.249642)
							(end 0.2794 0.1778)
						)
						(arc
							(start 0.2794 -0.1778)
							(mid 0.249642 -0.249642)
							(end 0.1778 -0.2794)
						)
					)
					(width 0)
					(fill yes)
				)
			)
		)
	)
	(footprint ""
		(layer "F.Cu")
		(at 32.78251 -171.677076)
		(property "Reference" "C12"
			(at 0 0 0)
			(layer "F.SilkS")
			(hide yes)
			(effects
				(font
					(size 1.27 1.27)
				)
			)
		)
		(property "Value" "SC1U16V3KX-5GP"
			(at 0 -2.8194 0)
			(unlocked yes)
			(layer "F.Fab")
			(hide yes)
			(effects
				(font
					(size 1.016 1.016)
					(thickness 0.1524)
				)
			)
		)
		(property "Device Type" "C603H36"
			(at 0 -4.3434 0)
			(unlocked yes)
			(layer "F.Fab")
			(hide yes)
			(effects
				(font
					(size 1.016 1.016)
					(thickness 0.1524)
				)
			)
		)
		(duplicate_pad_numbers_are_jumpers no)
		(fp_line
			(start 0.508 0)
			(end -0.508 0)
			(stroke
				(width 0.2032)
				(type default)
			)
			(layer "F.SilkS")
		)
		(fp_rect
			(start -0.5842 1.3335)
			(end 0.5842 -1.3335)
			(stroke
				(width 0)
				(type default)
			)
			(fill no)
			(layer "F.CrtYd")
		)
		(fp_rect
			(start -0.5842 1.3335)
			(end 0.5842 -1.3335)
			(stroke
				(width 0)
				(type default)
			)
			(fill no)
			(layer "F.Fab")
		)
		(pad "1" smd custom
			(at 0 -0.762)
			(size 0.2159 0.2159)
			(layers "F.Cu" "F.Mask" "F.Paste")
			(net "P3V3")
			(options
				(clearance outline)
				(anchor circle)
			)
			(primitives
				(gr_poly
					(pts
						(arc
							(start -0.3302 -0.4318)
							(mid -0.402042 -0.402042)
							(end -0.4318 -0.3302)
						)
						(arc
							(start -0.4318 0.3302)
							(mid -0.402042 0.402042)
							(end -0.3302 0.4318)
						)
						(arc
							(start 0.3302 0.4318)
							(mid 0.402042 0.402042)
							(end 0.4318 0.3302)
						)
						(arc
							(start 0.4318 -0.3302)
							(mid 0.402042 -0.402042)
							(end 0.3302 -0.4318)
						)
					)
					(width 0)
					(fill yes)
				)
			)
		)
		(pad "2" smd custom
			(at 0 0.762)
			(size 0.2159 0.2159)
			(layers "F.Cu" "F.Mask" "F.Paste")
			(net "GND")
			(options
				(clearance outline)
				(anchor circle)
			)
			(primitives
				(gr_poly
					(pts
						(arc
							(start -0.3302 -0.4318)
							(mid -0.402042 -0.402042)
							(end -0.4318 -0.3302)
						)
						(arc
							(start -0.4318 0.3302)
							(mid -0.402042 0.402042)
							(end -0.3302 0.4318)
						)
						(arc
							(start 0.3302 0.4318)
							(mid 0.402042 0.402042)
							(end 0.4318 0.3302)
						)
						(arc
							(start 0.4318 -0.3302)
							(mid 0.402042 -0.402042)
							(end 0.3302 -0.4318)
						)
					)
					(width 0)
					(fill yes)
				)
			)
		)
	)
	(footprint ""
		(layer "F.Cu")
		(at 8.001 -169.418 -90)
		(property "Reference" "TC14"
			(at 0 0 270)
			(layer "F.SilkS")
			(hide yes)
			(effects
				(font
					(size 1.27 1.27)
				)
			)
		)
		(property "Value" "ST15U25VDM-1-GP"
			(at 0 -9.6012 270)
			(unlocked yes)
			(layer "F.Fab")
			(hide yes)
			(effects
				(font
					(size 1.016 1.016)
					(thickness 0.1524)
				)
			)
		)
		(property "Device Type" "CT7343H79"
			(at 0 -11.1252 270)
			(unlocked yes)
			(layer "F.Fab")
			(hide yes)
			(effects
				(font
					(size 1.016 1.016)
					(thickness 0.1524)
				)
			)
		)
		(duplicate_pad_numbers_are_jumpers no)
		(fp_line
			(start -2.286 4.8768)
			(end -2.286 2.032)
			(stroke
				(width 0.1524)
				(type default)
			)
			(layer "F.SilkS")
		)
		(fp_line
			(start 2.286 4.8768)
			(end -2.286 4.8768)
			(stroke
				(width 0.1524)
				(type default)
			)
			(layer "F.SilkS")
		)
		(fp_line
			(start 2.286 2.032)
			(end 2.286 4.8768)
			(stroke
				(width 0.1524)
				(type default)
			)
			(layer "F.SilkS")
		)
		(fp_line
			(start 2.286 -2.032)
			(end 2.286 -4.8768)
			(stroke
				(width 0.1524)
				(type default)
			)
			(layer "F.SilkS")
		)
		(fp_line
			(start 2.1082 -4.699)
			(end -2.1082 -4.699)
			(stroke
				(width 0.508)
				(type default)
			)
			(layer "F.SilkS")
		)
		(fp_line
			(start -2.286 -4.8768)
			(end -2.286 -2.032)
			(stroke
				(width 0.1524)
				(type default)
			)
			(layer "F.SilkS")
		)
		(fp_line
			(start 2.286 -4.8768)
			(end -2.286 -4.8768)
			(stroke
				(width 0.1524)
				(type default)
			)
			(layer "F.SilkS")
		)
		(fp_rect
			(start -2.1463 3.6449)
			(end 2.1463 -3.6449)
			(stroke
				(width 0)
				(type default)
			)
			(fill no)
			(layer "F.CrtYd")
		)
		(fp_poly
			(pts
				(xy -2.54 4.953) (xy -2.54 4.2926) (xy -3.81 4.2926) (xy -3.81 -4.2926) (xy -2.54 -4.2926) (xy -2.54 -4.953)
				(xy 2.54 -4.953) (xy 2.54 -4.2926) (xy 3.81 -4.2926) (xy 3.81 -1.6256) (xy 2.1463 -1.6256) (xy 2.1463 -3.6449)
				(xy -2.1463 -3.6449) (xy -2.1463 3.6449) (xy 2.1463 3.6449) (xy 2.1463 -1.6129) (xy 3.81 -1.6129)
				(xy 3.81 4.2926) (xy 2.54 4.2926) (xy 2.54 4.953)
			)
			(stroke
				(width 0)
				(type default)
			)
			(fill no)
			(layer "F.CrtYd")
		)
		(fp_rect
			(start -2.54 4.953)
			(end 2.54 -4.953)
			(stroke
				(width 0)
				(type default)
			)
			(fill no)
			(layer "F.Fab")
		)
		(fp_rect
			(start -3.81 4.2926)
			(end -2.54 -4.2926)
			(stroke
				(width 0)
				(type default)
			)
			(fill no)
			(layer "F.Fab")
		)
		(fp_rect
			(start 2.54 4.2926)
			(end 3.81 -4.2926)
			(stroke
				(width 0)
				(type default)
			)
			(fill no)
			(layer "F.Fab")
		)
		(pad "1" smd rect
			(at 0 -3.1496 270)
			(size 2.413 2.286)
			(layers "F.Cu" "F.Mask" "F.Paste")
			(net "P12V")
		)
		(pad "2" smd rect
			(at 0 3.1496 270)
			(size 2.413 2.286)
			(layers "F.Cu" "F.Mask" "F.Paste")
			(net "GND")
		)
		(zone
			(layer "F.Cu")
			(hatch none 0.5)
			(connect_pads
				(clearance 0)
			)
			(min_thickness 0.25)
			(keepout
				(tracks allowed)
				(vias not_allowed)
				(pads allowed)
				(copperpour not_allowed)
				(footprints allowed)
			)
			(placement
				(enabled no)
				(sheetname "")
			)
			(fill
				(thermal_gap 0.5)
				(thermal_bridge_width 0.5)
				(island_removal_mode 0)
			)
			(polygon
				(pts
					(xy 3.4036 -170.9293) (xy 3.4036 -167.9067) (xy 6.2992 -167.9067) (xy 6.6294 -167.9067) (xy 6.6294 -170.9293)
					(xy 6.2992 -170.9293)
				)
			)
		)
		(zone
			(layer "F.Cu")
			(hatch none 0.5)
			(connect_pads
				(clearance 0)
			)
			(min_thickness 0.25)
			(keepout
				(tracks allowed)
				(vias not_allowed)
				(pads allowed)
				(copperpour not_allowed)
				(footprints allowed)
			)
			(placement
				(enabled no)
				(sheetname "")
			)
			(fill
				(thermal_gap 0.5)
				(thermal_bridge_width 0.5)
				(island_removal_mode 0)
			)
			(polygon
				(pts
					(xy 9.6901 -167.9067) (xy 12.5984 -167.9067) (xy 12.5984 -170.9293) (xy 9.7028 -170.9293) (xy 9.3726 -170.9293)
					(xy 9.3726 -167.9067)
				)
			)
		)
	)
	(footprint ""
		(layer "F.Cu")
		(at 8.89 -148.1074 180)
		(property "Reference" "C28"
			(at 0 0 180)
			(layer "F.SilkS")
			(hide yes)
			(effects
				(font
					(size 1.27 1.27)
				)
			)
		)
		(property "Value" "SCD1U16V2KX-3GP"
			(at 1.1811 -2.7051 180)
			(unlocked yes)
			(layer "F.Fab")
			(hide yes)
			(effects
				(font
					(size 1.016 1.016)
					(thickness 0.1524)
				)
			)
		)
		(property "Device Type" "C402H22"
			(at 1.1811 -4.2291 180)
			(unlocked yes)
			(layer "F.Fab")
			(hide yes)
			(effects
				(font
					(size 1.016 1.016)
					(thickness 0.1524)
				)
			)
		)
		(duplicate_pad_numbers_are_jumpers no)
		(fp_rect
			(start -0.4318 0.9525)
			(end 0.4318 -0.9525)
			(stroke
				(width 0)
				(type default)
			)
			(fill no)
			(layer "F.CrtYd")
		)
		(fp_rect
			(start -0.4318 0.9525)
			(end 0.4318 -0.9525)
			(stroke
				(width 0)
				(type default)
			)
			(fill no)
			(layer "F.Fab")
		)
		(pad "1" smd custom
			(at 0 -0.4445 180)
			(size 0.1524 0.1524)
			(layers "F.Cu" "F.Mask" "F.Paste")
			(net "FAN_TACH10")
			(options
				(clearance outline)
				(anchor circle)
			)
			(primitives
				(gr_poly
					(pts
						(arc
							(start 0.3048 -0.2032)
							(mid 0.275042 -0.275042)
							(end 0.2032 -0.3048)
						)
						(arc
							(start -0.2032 -0.3048)
							(mid -0.275042 -0.275042)
							(end -0.3048 -0.2032)
						)
						(arc
							(start -0.3048 0.2032)
							(mid -0.275042 0.275042)
							(end -0.2032 0.3048)
						)
						(arc
							(start 0.2032 0.3048)
							(mid 0.275042 0.275042)
							(end 0.3048 0.2032)
						)
					)
					(width 0)
					(fill yes)
				)
			)
		)
		(pad "2" smd custom
			(at 0 0.4445 180)
			(size 0.1524 0.1524)
			(layers "F.Cu" "F.Mask" "F.Paste")
			(net "GND")
			(options
				(clearance outline)
				(anchor circle)
			)
			(primitives
				(gr_poly
					(pts
						(arc
							(start 0.3048 -0.2032)
							(mid 0.275042 -0.275042)
							(end 0.2032 -0.3048)
						)
						(arc
							(start -0.2032 -0.3048)
							(mid -0.275042 -0.275042)
							(end -0.3048 -0.2032)
						)
						(arc
							(start -0.3048 0.2032)
							(mid -0.275042 0.275042)
							(end -0.2032 0.3048)
						)
						(arc
							(start 0.2032 0.3048)
							(mid 0.275042 0.275042)
							(end 0.3048 0.2032)
						)
					)
					(width 0)
					(fill yes)
				)
			)
		)
	)
	(footprint ""
		(layer "F.Cu")
		(at 31.122366 -242.327176)
		(property "Reference" "R44"
			(at 0 0 0)
			(layer "F.SilkS")
			(hide yes)
			(effects
				(font
					(size 1.27 1.27)
				)
			)
		)
		(property "Value" "4K7R2J-2-GP"
			(at 0.064008 -3.993896 0)
			(unlocked yes)
			(layer "F.Fab")
			(hide yes)
			(effects
				(font
					(size 1.016 1.016)
					(thickness 0.1524)
				)
			)
		)
		(property "Device Type" "R402H16"
			(at 0.064008 -5.517896 0)
			(unlocked yes)
			(layer "F.Fab")
			(hide yes)
			(effects
				(font
					(size 1.016 1.016)
					(thickness 0.1524)
				)
			)
		)
		(duplicate_pad_numbers_are_jumpers no)
		(fp_line
			(start -0.508 -0.9398)
			(end -0.508 0.9398)
			(stroke
				(width 0.1524)
				(type default)
			)
			(layer "F.SilkS")
		)
		(fp_line
			(start 0.508 -0.9398)
			(end -0.508 -0.9398)
			(stroke
				(width 0.1524)
				(type default)
			)
			(layer "F.SilkS")
		)
		(fp_rect
			(start -0.508 0.9398)
			(end 0.508 -0.9398)
			(stroke
				(width 0)
				(type default)
			)
			(fill no)
			(layer "F.CrtYd")
		)
		(fp_rect
			(start -0.508 0.9398)
			(end 0.508 -0.9398)
			(stroke
				(width 0)
				(type default)
			)
			(fill no)
			(layer "F.Fab")
		)
		(pad "1" smd custom
			(at 0 -0.4445)
			(size 0.1397 0.1397)
			(layers "F.Cu" "F.Mask" "F.Paste")
			(net "FCB_EEPROM_A2")
			(options
				(clearance outline)
				(anchor circle)
			)
			(primitives
				(gr_poly
					(pts
						(arc
							(start -0.1778 -0.2794)
							(mid -0.249642 -0.249642)
							(end -0.2794 -0.1778)
						)
						(arc
							(start -0.2794 0.1778)
							(mid -0.249642 0.249642)
							(end -0.1778 0.2794)
						)
						(arc
							(start 0.1778 0.2794)
							(mid 0.249642 0.249642)
							(end 0.2794 0.1778)
						)
						(arc
							(start 0.2794 -0.1778)
							(mid 0.249642 -0.249642)
							(end 0.1778 -0.2794)
						)
					)
					(width 0)
					(fill yes)
				)
			)
		)
		(pad "2" smd custom
			(at 0 0.4445)
			(size 0.1397 0.1397)
			(layers "F.Cu" "F.Mask" "F.Paste")
			(net "GND")
			(options
				(clearance outline)
				(anchor circle)
			)
			(primitives
				(gr_poly
					(pts
						(arc
							(start -0.1778 -0.2794)
							(mid -0.249642 -0.249642)
							(end -0.2794 -0.1778)
						)
						(arc
							(start -0.2794 0.1778)
							(mid -0.249642 0.249642)
							(end -0.1778 0.2794)
						)
						(arc
							(start 0.1778 0.2794)
							(mid 0.249642 0.249642)
							(end 0.2794 0.1778)
						)
						(arc
							(start 0.2794 -0.1778)
							(mid 0.249642 -0.249642)
							(end 0.1778 -0.2794)
						)
					)
					(width 0)
					(fill yes)
				)
			)
		)
	)
	(footprint ""
		(layer "F.Cu")
		(at 28.067 -238.252 180)
		(property "Reference" "R39"
			(at 0 0 180)
			(layer "F.SilkS")
			(hide yes)
			(effects
				(font
					(size 1.27 1.27)
				)
			)
		)
		(property "Value" "4K7R2J-2-GP"
			(at 0.064008 -3.993896 180)
			(unlocked yes)
			(layer "F.Fab")
			(hide yes)
			(effects
				(font
					(size 1.016 1.016)
					(thickness 0.1524)
				)
			)
		)
		(property "Device Type" "R402H16"
			(at 0.064008 -5.517896 180)
			(unlocked yes)
			(layer "F.Fab")
			(hide yes)
			(effects
				(font
					(size 1.016 1.016)
					(thickness 0.1524)
				)
			)
		)
		(duplicate_pad_numbers_are_jumpers no)
		(fp_line
			(start 0.508 -0.9398)
			(end -0.508 -0.9398)
			(stroke
				(width 0.1524)
				(type default)
			)
			(layer "F.SilkS")
		)
		(fp_line
			(start -0.508 -0.9398)
			(end -0.508 0.9398)
			(stroke
				(width 0.1524)
				(type default)
			)
			(layer "F.SilkS")
		)
		(fp_rect
			(start -0.508 0.9398)
			(end 0.508 -0.9398)
			(stroke
				(width 0)
				(type default)
			)
			(fill no)
			(layer "F.CrtYd")
		)
		(fp_rect
			(start -0.508 0.9398)
			(end 0.508 -0.9398)
			(stroke
				(width 0)
				(type default)
			)
			(fill no)
			(layer "F.Fab")
		)
		(pad "1" smd custom
			(at 0 -0.4445 180)
			(size 0.1397 0.1397)
			(layers "F.Cu" "F.Mask" "F.Paste")
			(net "P3V3")
			(options
				(clearance outline)
				(anchor circle)
			)
			(primitives
				(gr_poly
					(pts
						(arc
							(start -0.1778 -0.2794)
							(mid -0.249642 -0.249642)
							(end -0.2794 -0.1778)
						)
						(arc
							(start -0.2794 0.1778)
							(mid -0.249642 0.249642)
							(end -0.1778 0.2794)
						)
						(arc
							(start 0.1778 0.2794)
							(mid 0.249642 0.249642)
							(end 0.2794 0.1778)
						)
						(arc
							(start 0.2794 -0.1778)
							(mid 0.249642 -0.249642)
							(end 0.1778 -0.2794)
						)
					)
					(width 0)
					(fill yes)
				)
			)
		)
		(pad "2" smd custom
			(at 0 0.4445 180)
			(size 0.1397 0.1397)
			(layers "F.Cu" "F.Mask" "F.Paste")
			(net "FCB_EEPROM_A0")
			(options
				(clearance outline)
				(anchor circle)
			)
			(primitives
				(gr_poly
					(pts
						(arc
							(start -0.1778 -0.2794)
							(mid -0.249642 -0.249642)
							(end -0.2794 -0.1778)
						)
						(arc
							(start -0.2794 0.1778)
							(mid -0.249642 0.249642)
							(end -0.1778 0.2794)
						)
						(arc
							(start 0.1778 0.2794)
							(mid 0.249642 0.249642)
							(end 0.2794 0.1778)
						)
						(arc
							(start 0.2794 -0.1778)
							(mid 0.249642 -0.249642)
							(end 0.1778 -0.2794)
						)
					)
					(width 0)
					(fill yes)
				)
			)
		)
	)
	(footprint ""
		(layer "F.Cu")
		(at 17.8816 -255.0922 -90)
		(property "Reference" "R82"
			(at 0 0 270)
			(layer "F.SilkS")
			(hide yes)
			(effects
				(font
					(size 1.27 1.27)
				)
			)
		)
		(property "Value" "4K7R2F-GP"
			(at 0.064008 -3.993896 270)
			(unlocked yes)
			(layer "F.Fab")
			(hide yes)
			(effects
				(font
					(size 1.016 1.016)
					(thickness 0.1524)
				)
			)
		)
		(property "Device Type" "R402H16"
			(at 0.064008 -5.517896 270)
			(unlocked yes)
			(layer "F.Fab")
			(hide yes)
			(effects
				(font
					(size 1.016 1.016)
					(thickness 0.1524)
				)
			)
		)
		(duplicate_pad_numbers_are_jumpers no)
		(fp_line
			(start -0.508 -0.9398)
			(end -0.508 0.9398)
			(stroke
				(width 0.1524)
				(type default)
			)
			(layer "F.SilkS")
		)
		(fp_line
			(start 0.508 -0.9398)
			(end -0.508 -0.9398)
			(stroke
				(width 0.1524)
				(type default)
			)
			(layer "F.SilkS")
		)
		(fp_rect
			(start -0.508 0.9398)
			(end 0.508 -0.9398)
			(stroke
				(width 0)
				(type default)
			)
			(fill no)
			(layer "F.CrtYd")
		)
		(fp_rect
			(start -0.508 0.9398)
			(end 0.508 -0.9398)
			(stroke
				(width 0)
				(type default)
			)
			(fill no)
			(layer "F.Fab")
		)
		(pad "1" smd custom
			(at 0 -0.4445 270)
			(size 0.1397 0.1397)
			(layers "F.Cu" "F.Mask" "F.Paste")
			(net "P12V")
			(options
				(clearance outline)
				(anchor circle)
			)
			(primitives
				(gr_poly
					(pts
						(arc
							(start -0.1778 -0.2794)
							(mid -0.249642 -0.249642)
							(end -0.2794 -0.1778)
						)
						(arc
							(start -0.2794 0.1778)
							(mid -0.249642 0.249642)
							(end -0.1778 0.2794)
						)
						(arc
							(start 0.1778 0.2794)
							(mid 0.249642 0.249642)
							(end 0.2794 0.1778)
						)
						(arc
							(start 0.2794 -0.1778)
							(mid 0.249642 -0.249642)
							(end 0.1778 -0.2794)
						)
					)
					(width 0)
					(fill yes)
				)
			)
		)
		(pad "2" smd custom
			(at 0 0.4445 270)
			(size 0.1397 0.1397)
			(layers "F.Cu" "F.Mask" "F.Paste")
			(net "FAN_TACH5")
			(options
				(clearance outline)
				(anchor circle)
			)
			(primitives
				(gr_poly
					(pts
						(arc
							(start -0.1778 -0.2794)
							(mid -0.249642 -0.249642)
							(end -0.2794 -0.1778)
						)
						(arc
							(start -0.2794 0.1778)
							(mid -0.249642 0.249642)
							(end -0.1778 0.2794)
						)
						(arc
							(start 0.1778 0.2794)
							(mid 0.249642 0.249642)
							(end 0.2794 0.1778)
						)
						(arc
							(start 0.2794 -0.1778)
							(mid 0.249642 -0.249642)
							(end 0.1778 -0.2794)
						)
					)
					(width 0)
					(fill yes)
				)
			)
		)
	)
)
